# T6G (Grand Teton) — schematic netlist excerpt (pin names and nets, part order shuffled) for the footprints in the layout excerpt that follows; sources: Cadence DE-HDL packaged netlist, KiCad conversion of 04192023_DAF0TMB3IC0_F0TG_MB_C_brd_V02_OCP.brd

R6227  Q_RES  10K 1% EMPTY  pkg 0402LF  page 176 : A = P3V3_AUX ; B = SMB_USB_CPU0_HUB1_SDA_R2
C2354  Q_CAP  22UF 4V 20% X6S  pkg C0402  page 73 : A = PVDDCR_CPU1_P1 ; B = GND

(kicad_pcb
	(version 20260206)
	(generator "pcbnew")
	(generator_version "10.0")
	(general
		(thickness 1.6)
		(legacy_teardrops no)
	)
	(paper "A4")
	(title_block
		(title "04192023_DAF0TMB3IC0_F0TG_MB_C_brd_V02_OCP.brd")
		(comment 1 "Grand Teton / footprints 7643-7644 of 8354")
	)
	(layers
		(0 "F.Cu" signal "TOP")
		(4 "In1.Cu" signal "GND")
		(6 "In2.Cu" signal "IN1")
		(8 "In3.Cu" signal "GND1")
		(10 "In4.Cu" signal "IN2")
		(12 "In5.Cu" signal "GND2")
		(14 "In6.Cu" signal "IN3")
		(16 "In7.Cu" signal "GND3")
		(18 "In8.Cu" signal "VCC")
		(20 "In9.Cu" signal "VCC1")
		(22 "In10.Cu" signal "GND4")
		(24 "In11.Cu" signal "IN4")
		(26 "In12.Cu" signal "GND5")
		(28 "In13.Cu" signal "IN5")
		(30 "In14.Cu" signal "GND6")
		(32 "In15.Cu" signal "IN6")
		(34 "In16.Cu" signal "GND7")
		(2 "B.Cu" signal "BOTTOM")
		(9 "F.Adhes" user "F.Adhesive")
		(11 "B.Adhes" user "B.Adhesive")
		(13 "F.Paste" user "Package Geometry/Pastemask Top")
		(15 "B.Paste" user "Package Geometry/Pastemask Bottom")
		(5 "F.SilkS" user "Ref Des/Silkscreen Top")
		(7 "B.SilkS" user "Ref Des/Silkscreen Bottom")
		(1 "F.Mask" user "Board Geometry/Soldermask Top")
		(3 "B.Mask" user "Board Geometry/Soldermask Bottom")
		(17 "Dwgs.User" user "User.Drawings")
		(19 "Cmts.User" user "User.Comments")
		(21 "Eco1.User" user "User.Eco1")
		(23 "Eco2.User" user "User.Eco2")
		(25 "Edge.Cuts" user "Board Geometry/Outline")
		(27 "Margin" user)
		(31 "F.CrtYd" user "Package Geometry/Place Bound Top")
		(29 "B.CrtYd" user "Package Geometry/Place Bound Bottom")
		(35 "F.Fab" user "Ref Des/Assembly Top")
		(33 "B.Fab" user "Ref Des/Assembly Bottom")
	)
	(footprint ""
		(layer "B.Cu")
		(at 107.383834 -272.284952 180)
		(property "Reference" "C2354"
			(at 0 0 0)
			(layer "B.SilkS")
			(hide yes)
			(effects
				(font
					(size 1.27 1.27)
				)
				(justify mirror)
			)
		)
		(property "Value" ""
			(at 0 0 0)
			(layer "B.Fab")
			(effects
				(font
					(size 1.27 1.27)
				)
				(justify mirror)
			)
		)
		(duplicate_pad_numbers_are_jumpers no)
		(fp_line
			(start 0.7874 0.4064)
			(end 0.7874 -0.4064)
			(stroke
				(width 0.1524)
				(type default)
			)
			(layer "B.SilkS")
		)
		(fp_line
			(start 0.7874 -0.4064)
			(end -0.7874 -0.4064)
			(stroke
				(width 0.1524)
				(type default)
			)
			(layer "B.SilkS")
		)
		(fp_line
			(start -0.7874 0.4064)
			(end 0.7874 0.4064)
			(stroke
				(width 0.1524)
				(type default)
			)
			(layer "B.SilkS")
		)
		(fp_line
			(start -0.7874 -0.4064)
			(end -0.7874 0.4064)
			(stroke
				(width 0.1524)
				(type default)
			)
			(layer "B.SilkS")
		)
		(fp_line
			(start 0.67945 0.3048)
			(end 0.67945 -0.305054)
			(stroke
				(width 0.1)
				(type default)
			)
			(layer "B.Fab")
		)
		(fp_line
			(start 0.67945 -0.305054)
			(end 0.12065 -0.305054)
			(stroke
				(width 0.1)
				(type default)
			)
			(layer "B.Fab")
		)
		(fp_line
			(start 0.12065 0.3048)
			(end 0.67945 0.3048)
			(stroke
				(width 0.1)
				(type default)
			)
			(layer "B.Fab")
		)
		(fp_line
			(start 0.12065 0.2794)
			(end 0.12065 0.3048)
			(stroke
				(width 0.1)
				(type default)
			)
			(layer "B.Fab")
		)
		(fp_line
			(start 0.12065 -0.2794)
			(end -0.12065 -0.2794)
			(stroke
				(width 0.1)
				(type default)
			)
			(layer "B.Fab")
		)
		(fp_line
			(start 0.12065 -0.305054)
			(end 0.12065 -0.2794)
			(stroke
				(width 0.1)
				(type default)
			)
			(layer "B.Fab")
		)
		(fp_line
			(start -0.120396 0.3048)
			(end -0.120396 0.2794)
			(stroke
				(width 0.1)
				(type default)
			)
			(layer "B.Fab")
		)
		(fp_line
			(start -0.120396 0.2794)
			(end 0.12065 0.2794)
			(stroke
				(width 0.1)
				(type default)
			)
			(layer "B.Fab")
		)
		(fp_line
			(start -0.12065 -0.2794)
			(end -0.12065 -0.3048)
			(stroke
				(width 0.1)
				(type default)
			)
			(layer "B.Fab")
		)
		(fp_line
			(start -0.12065 -0.3048)
			(end -0.67945 -0.3048)
			(stroke
				(width 0.1)
				(type default)
			)
			(layer "B.Fab")
		)
		(fp_line
			(start -0.67945 0.3048)
			(end -0.120396 0.3048)
			(stroke
				(width 0.1)
				(type default)
			)
			(layer "B.Fab")
		)
		(fp_line
			(start -0.67945 -0.3048)
			(end -0.67945 0.3048)
			(stroke
				(width 0.1)
				(type default)
			)
			(layer "B.Fab")
		)
		(pad "1" smd circle
			(at 0.40005 0)
			(size 0 0)
			(layers "B.Cu" "B.Mask" "B.Paste")
			(net "PVDDCR_CPU1_P1")
		)
		(pad "2" smd circle
			(at -0.40005 0)
			(size 0 0)
			(layers "B.Cu" "B.Mask" "B.Paste")
			(net "GND")
		)
	)
	(footprint ""
		(layer "B.Cu")
		(at 114.73434 -61.76391 -90)
		(property "Reference" "R6227"
			(at 0 0 90)
			(layer "B.SilkS")
			(hide yes)
			(effects
				(font
					(size 1.27 1.27)
				)
				(justify mirror)
			)
		)
		(property "Value" ""
			(at 0 0 90)
			(layer "B.Fab")
			(effects
				(font
					(size 1.27 1.27)
				)
				(justify mirror)
			)
		)
		(duplicate_pad_numbers_are_jumpers no)
		(fp_line
			(start -0.7874 0.4064)
			(end 0.7874 0.4064)
			(stroke
				(width 0.1524)
				(type default)
			)
			(layer "B.SilkS")
		)
		(fp_line
			(start 0.7874 0.4064)
			(end 0.7874 -0.4064)
			(stroke
				(width 0.1524)
				(type default)
			)
			(layer "B.SilkS")
		)
		(fp_line
			(start -0.7874 -0.4064)
			(end -0.7874 0.4064)
			(stroke
				(width 0.1524)
				(type default)
			)
			(layer "B.SilkS")
		)
		(fp_line
			(start 0.7874 -0.4064)
			(end -0.7874 -0.4064)
			(stroke
				(width 0.1524)
				(type default)
			)
			(layer "B.SilkS")
		)
		(fp_line
			(start -0.67945 0.3048)
			(end -0.120396 0.3048)
			(stroke
				(width 0.1)
				(type default)
			)
			(layer "B.Fab")
		)
		(fp_line
			(start -0.120396 0.3048)
			(end -0.120396 0.2794)
			(stroke
				(width 0.1)
				(type default)
			)
			(layer "B.Fab")
		)
		(fp_line
			(start 0.12065 0.3048)
			(end 0.67945 0.3048)
			(stroke
				(width 0.1)
				(type default)
			)
			(layer "B.Fab")
		)
		(fp_line
			(start 0.67945 0.3048)
			(end 0.67945 -0.305054)
			(stroke
				(width 0.1)
				(type default)
			)
			(layer "B.Fab")
		)
		(fp_line
			(start -0.120396 0.2794)
			(end 0.12065 0.2794)
			(stroke
				(width 0.1)
				(type default)
			)
			(layer "B.Fab")
		)
		(fp_line
			(start 0.12065 0.2794)
			(end 0.12065 0.3048)
			(stroke
				(width 0.1)
				(type default)
			)
			(layer "B.Fab")
		)
		(fp_line
			(start -0.12065 -0.2794)
			(end -0.12065 -0.3048)
			(stroke
				(width 0.1)
				(type default)
			)
			(layer "B.Fab")
		)
		(fp_line
			(start 0.12065 -0.2794)
			(end -0.12065 -0.2794)
			(stroke
				(width 0.1)
				(type default)
			)
			(layer "B.Fab")
		)
		(fp_line
			(start -0.67945 -0.3048)
			(end -0.67945 0.3048)
			(stroke
				(width 0.1)
				(type default)
			)
			(layer "B.Fab")
		)
		(fp_line
			(start -0.12065 -0.3048)
			(end -0.67945 -0.3048)
			(stroke
				(width 0.1)
				(type default)
			)
			(layer "B.Fab")
		)
		(fp_line
			(start 0.12065 -0.305054)
			(end 0.12065 -0.2794)
			(stroke
				(width 0.1)
				(type default)
			)
			(layer "B.Fab")
		)
		(fp_line
			(start 0.67945 -0.305054)
			(end 0.12065 -0.305054)
			(stroke
				(width 0.1)
				(type default)
			)
			(layer "B.Fab")
		)
		(pad "1" smd circle
			(at 0.40005 0 90)
			(size 0 0)
			(layers "B.Cu" "B.Mask" "B.Paste")
			(net "P3V3_AUX")
		)
		(pad "2" smd circle
			(at -0.40005 0 90)
			(size 0 0)
			(layers "B.Cu" "B.Mask" "B.Paste")
			(net "SMB_USB_CPU0_HUB1_SDA_R2")
		)
	)
)
